# S9S_MB_2U (Grand Teton) — schematic netlist excerpt (pin names and nets, part order shuffled) for the footprints in the layout excerpt that follows; sources: Cadence DE-HDL packaged netlist, KiCad conversion of 03242023_DA0F0TMBIJ0_F0T_Motherboard_J_brd_V01_OCP.brd

R4101  Q_RES  10K 1% CHIP  pkg 0402LF  page 183 : A = PD_PCH_GPPC_C9 ; B = GND
R1929  Q_RES  10K 1% CHIP  pkg 0402LF  page 153 : A = GND ; B = OCP_SFF_AUX_PWR_EN

(kicad_pcb
	(version 20260206)
	(generator "pcbnew")
	(generator_version "10.0")
	(general
		(thickness 1.6)
		(legacy_teardrops no)
	)
	(paper "A4")
	(title_block
		(title "03242023_DA0F0TMBIJ0_F0T_Motherboard_J_brd_V01_OCP.brd")
		(comment 1 "Grand Teton / footprints 1571-1572 of 6105")
	)
	(layers
		(0 "F.Cu" signal "TOP")
		(4 "In1.Cu" signal "GND")
		(6 "In2.Cu" signal "IN1")
		(8 "In3.Cu" signal "GND1")
		(10 "In4.Cu" signal "IN2")
		(12 "In5.Cu" signal "GND2")
		(14 "In6.Cu" signal "IN3")
		(16 "In7.Cu" signal "GND3")
		(18 "In8.Cu" signal "VCC")
		(20 "In9.Cu" signal "VCC1")
		(22 "In10.Cu" signal "GND4")
		(24 "In11.Cu" signal "IN4")
		(26 "In12.Cu" signal "GND5")
		(28 "In13.Cu" signal "IN5")
		(30 "In14.Cu" signal "GND6")
		(32 "In15.Cu" signal "IN6")
		(34 "In16.Cu" signal "GND7")
		(2 "B.Cu" signal "BOTTOM")
		(9 "F.Adhes" user "F.Adhesive")
		(11 "B.Adhes" user "B.Adhesive")
		(13 "F.Paste" user "Package Geometry/Pastemask Top")
		(15 "B.Paste" user "Package Geometry/Pastemask Bottom")
		(5 "F.SilkS" user "Ref Des/Silkscreen Top")
		(7 "B.SilkS" user "Ref Des/Silkscreen Bottom")
		(1 "F.Mask" user "Board Geometry/Soldermask Top")
		(3 "B.Mask" user "Board Geometry/Soldermask Bottom")
		(17 "Dwgs.User" user "User.Drawings")
		(19 "Cmts.User" user "User.Comments")
		(21 "Eco1.User" user "User.Eco1")
		(23 "Eco2.User" user "User.Eco2")
		(25 "Edge.Cuts" user "Board Geometry/Outline")
		(27 "Margin" user)
		(31 "F.CrtYd" user "Package Geometry/Place Bound Top")
		(29 "B.CrtYd" user "Package Geometry/Place Bound Bottom")
		(35 "F.Fab" user "Ref Des/Assembly Top")
		(33 "B.Fab" user "Ref Des/Assembly Bottom")
	)
	(footprint ""
		(layer "F.Cu")
		(at 434.805328 -19.614134 -90)
		(property "Reference" "R1929"
			(at 0 0 270)
			(layer "F.SilkS")
			(hide yes)
			(effects
				(font
					(size 1.27 1.27)
				)
			)
		)
		(property "Value" ""
			(at 0 0 270)
			(layer "F.Fab")
			(effects
				(font
					(size 1.27 1.27)
				)
			)
		)
		(duplicate_pad_numbers_are_jumpers no)
		(fp_line
			(start -0.7874 0.4064)
			(end -0.7874 -0.4064)
			(stroke
				(width 0.1524)
				(type default)
			)
			(layer "F.SilkS")
		)
		(fp_line
			(start 0.7874 0.4064)
			(end -0.7874 0.4064)
			(stroke
				(width 0.1524)
				(type default)
			)
			(layer "F.SilkS")
		)
		(fp_line
			(start -0.7874 -0.4064)
			(end 0.7874 -0.4064)
			(stroke
				(width 0.1524)
				(type default)
			)
			(layer "F.SilkS")
		)
		(fp_line
			(start 0.7874 -0.4064)
			(end 0.7874 0.4064)
			(stroke
				(width 0.1524)
				(type default)
			)
			(layer "F.SilkS")
		)
		(fp_line
			(start -0.67945 0.3048)
			(end -0.67945 -0.305054)
			(stroke
				(width 0.1)
				(type default)
			)
			(layer "F.Fab")
		)
		(fp_line
			(start -0.12065 0.3048)
			(end -0.67945 0.3048)
			(stroke
				(width 0.1)
				(type default)
			)
			(layer "F.Fab")
		)
		(fp_line
			(start 0.120396 0.3048)
			(end 0.120396 0.2794)
			(stroke
				(width 0.1)
				(type default)
			)
			(layer "F.Fab")
		)
		(fp_line
			(start 0.67945 0.3048)
			(end 0.120396 0.3048)
			(stroke
				(width 0.1)
				(type default)
			)
			(layer "F.Fab")
		)
		(fp_line
			(start -0.12065 0.2794)
			(end -0.12065 0.3048)
			(stroke
				(width 0.1)
				(type default)
			)
			(layer "F.Fab")
		)
		(fp_line
			(start 0.120396 0.2794)
			(end -0.12065 0.2794)
			(stroke
				(width 0.1)
				(type default)
			)
			(layer "F.Fab")
		)
		(fp_line
			(start -0.12065 -0.2794)
			(end 0.12065 -0.2794)
			(stroke
				(width 0.1)
				(type default)
			)
			(layer "F.Fab")
		)
		(fp_line
			(start 0.12065 -0.2794)
			(end 0.12065 -0.3048)
			(stroke
				(width 0.1)
				(type default)
			)
			(layer "F.Fab")
		)
		(fp_line
			(start 0.12065 -0.3048)
			(end 0.67945 -0.3048)
			(stroke
				(width 0.1)
				(type default)
			)
			(layer "F.Fab")
		)
		(fp_line
			(start 0.67945 -0.3048)
			(end 0.67945 0.3048)
			(stroke
				(width 0.1)
				(type default)
			)
			(layer "F.Fab")
		)
		(fp_line
			(start -0.67945 -0.305054)
			(end -0.12065 -0.305054)
			(stroke
				(width 0.1)
				(type default)
			)
			(layer "F.Fab")
		)
		(fp_line
			(start -0.12065 -0.305054)
			(end -0.12065 -0.2794)
			(stroke
				(width 0.1)
				(type default)
			)
			(layer "F.Fab")
		)
		(pad "1" smd circle
			(at -0.40005 0 270)
			(size 0 0)
			(layers "F.Cu" "F.Mask" "F.Paste")
			(net "GND")
		)
		(pad "2" smd circle
			(at 0.40005 0 270)
			(size 0 0)
			(layers "F.Cu" "F.Mask" "F.Paste")
			(net "OCP_SFF_AUX_PWR_EN")
		)
	)
	(footprint ""
		(layer "F.Cu")
		(at 309.523638 -37.822886 180)
		(property "Reference" "R4101"
			(at 0 0 180)
			(layer "F.SilkS")
			(hide yes)
			(effects
				(font
					(size 1.27 1.27)
				)
			)
		)
		(property "Value" ""
			(at 0 0 180)
			(layer "F.Fab")
			(effects
				(font
					(size 1.27 1.27)
				)
			)
		)
		(duplicate_pad_numbers_are_jumpers no)
		(fp_line
			(start 0.7874 0.4064)
			(end -0.7874 0.4064)
			(stroke
				(width 0.1524)
				(type default)
			)
			(layer "F.SilkS")
		)
		(fp_line
			(start 0.7874 -0.4064)
			(end 0.7874 0.4064)
			(stroke
				(width 0.1524)
				(type default)
			)
			(layer "F.SilkS")
		)
		(fp_line
			(start -0.7874 0.4064)
			(end -0.7874 -0.4064)
			(stroke
				(width 0.1524)
				(type default)
			)
			(layer "F.SilkS")
		)
		(fp_line
			(start -0.7874 -0.4064)
			(end 0.7874 -0.4064)
			(stroke
				(width 0.1524)
				(type default)
			)
			(layer "F.SilkS")
		)
		(fp_line
			(start 0.67945 0.3048)
			(end 0.120396 0.3048)
			(stroke
				(width 0.1)
				(type default)
			)
			(layer "F.Fab")
		)
		(fp_line
			(start 0.67945 -0.3048)
			(end 0.67945 0.3048)
			(stroke
				(width 0.1)
				(type default)
			)
			(layer "F.Fab")
		)
		(fp_line
			(start 0.12065 -0.2794)
			(end 0.12065 -0.3048)
			(stroke
				(width 0.1)
				(type default)
			)
			(layer "F.Fab")
		)
		(fp_line
			(start 0.12065 -0.3048)
			(end 0.67945 -0.3048)
			(stroke
				(width 0.1)
				(type default)
			)
			(layer "F.Fab")
		)
		(fp_line
			(start 0.120396 0.3048)
			(end 0.120396 0.2794)
			(stroke
				(width 0.1)
				(type default)
			)
			(layer "F.Fab")
		)
		(fp_line
			(start 0.120396 0.2794)
			(end -0.12065 0.2794)
			(stroke
				(width 0.1)
				(type default)
			)
			(layer "F.Fab")
		)
		(fp_line
			(start -0.12065 0.3048)
			(end -0.67945 0.3048)
			(stroke
				(width 0.1)
				(type default)
			)
			(layer "F.Fab")
		)
		(fp_line
			(start -0.12065 0.2794)
			(end -0.12065 0.3048)
			(stroke
				(width 0.1)
				(type default)
			)
			(layer "F.Fab")
		)
		(fp_line
			(start -0.12065 -0.2794)
			(end 0.12065 -0.2794)
			(stroke
				(width 0.1)
				(type default)
			)
			(layer "F.Fab")
		)
		(fp_line
			(start -0.12065 -0.305054)
			(end -0.12065 -0.2794)
			(stroke
				(width 0.1)
				(type default)
			)
			(layer "F.Fab")
		)
		(fp_line
			(start -0.67945 0.3048)
			(end -0.67945 -0.305054)
			(stroke
				(width 0.1)
				(type default)
			)
			(layer "F.Fab")
		)
		(fp_line
			(start -0.67945 -0.305054)
			(end -0.12065 -0.305054)
			(stroke
				(width 0.1)
				(type default)
			)
			(layer "F.Fab")
		)
		(pad "1" smd circle
			(at -0.40005 0 180)
			(size 0 0)
			(layers "F.Cu" "F.Mask" "F.Paste")
			(net "PD_PCH_GPPC_C9")
		)
		(pad "2" smd circle
			(at 0.40005 0 180)
			(size 0 0)
			(layers "F.Cu" "F.Mask" "F.Paste")
			(net "GND")
		)
	)
)
